#ISCELL
  mstr_misc dns *
  *
#ISCELL
  mstr_symbols design_note *
  *
#ISCELL
  mstr_symbols intel_corp_bpage *
  *
#CELL
  mstr_controller adm1278 *
  page199_i10
#CELL
  mstr_discrete res *
  page199_i100
#ISCELL
  mstr_symbols agnd0 *
  page199_i101
#CELL
  mstr_discrete res *
  page199_i102
#CELL
  dev_discrete cap_a *
  page199_i105
#ISCELL
  mstr_symbols agnd0 *
  page199_i106
#CELL
  dev_discrete cap_a *
  page199_i107
#CELL
  mstr_discrete res *
  page199_i108
#CELL
  mstr_discrete res *
  page199_i109
#ISCELL
  mstr_symbols gnd *
  page199_i11
#CELL
  mstr_discrete res *
  page199_i110
#ISCELL
  mstr_symbols agnd0 *
  page199_i112
#ISCELL
  mstr_symbols agnd0 *
  page199_i113
#ISCELL
  mstr_symbols agnd0 *
  page199_i115
#ISCELL
  mstr_symbols gnd *
  page199_i116
#ISCELL
  mstr_symbols agnd0 *
  page199_i117
#ISCELL
  mstr_symbols agnd0 *
  page199_i118
#CELL
  mstr_discrete cap *
  page199_i119
#CELL
  mstr_discrete res *
  page199_i12
#ISCELL
  mstr_symbols agnd0 *
  page199_i120
#CELL
  dev_discrete cap_a *
  page199_i121
#ISCELL
  mstr_symbols agnd0 *
  page199_i122
#ISCELL
  mstr_standard offpage *
  page199_i125
#ISCELL
  mstr_standard offpage *
  page199_i126
#ISCELL
  mstr_symbols gnd *
  page199_i128
#ISCELL
  mstr_standard offpage *
  page199_i129
#CELL
  mstr_discrete res *
  page199_i13
#CELL
  mstr_discrete fet_n *
  page199_i130
#CELL
  w_hdl clx-conn3a-1-gp *
  page199_i131
#CELL
  mstr_discrete cap *
  page199_i132
#ISCELL
  mstr_symbols gnd *
  page199_i133
#CELL
  mstr_discrete res *
  page199_i134
#CELL
  mstr_discrete res *
  page199_i135
#CELL
  mstr_discrete res *
  page199_i137
#CELL
  mstr_discrete res *
  page199_i138
#CELL
  mstr_discrete res *
  page199_i15
#CELL
  mstr_discrete res *
  page199_i16
#CELL
  mstr_discrete res *
  page199_i17
#ISCELL
  mstr_symbols agnd0 *
  page199_i18
#CELL
  mstr_discrete res *
  page199_i19
#CELL
  mstr_discrete res *
  page199_i2
#ISCELL
  mstr_symbols gnd *
  page199_i20
#ISCELL
  mstr_symbols agnd0 *
  page199_i21
#ISCELL
  mstr_symbols agnd0 *
  page199_i23
#CELL
  mstr_discrete cap *
  page199_i24
#CELL
  mstr_discrete res *
  page199_i26
#CELL
  mstr_discrete res *
  page199_i27
#CELL
  mstr_discrete res *
  page199_i28
#CELL
  mstr_discrete cap *
  page199_i3
#ISCELL
  mstr_standard offpage *
  page199_i30
#ISCELL
  mstr_standard offpage *
  page199_i31
#CELL
  mstr_discrete res *
  page199_i33
#ISCELL
  mstr_symbols agnd0 *
  page199_i34
#CELL
  mstr_discrete res *
  page199_i36
#CELL
  mstr_discrete res *
  page199_i38
#CELL
  mstr_discrete res *
  page199_i41
#CELL
  mstr_discrete res *
  page199_i43
#ISCELL
  mstr_symbols gnd *
  page199_i44
#ISCELL
  mstr_standard offpage *
  page199_i45
#ISCELL
  mstr_standard offpage *
  page199_i49
#ISCELL
  mstr_standard offpage *
  page199_i50
#ISCELL
  mstr_symbols agnd0 *
  page199_i52
#CELL
  dev_discrete cap_a *
  page199_i53
#CELL
  mstr_discrete res *
  page199_i54
#CELL
  mstr_discrete res *
  page199_i55
#ISCELL
  mstr_symbols agnd0 *
  page199_i56
#CELL
  mstr_discrete npn *
  page199_i58
#ISCELL
  mstr_standard offpage *
  page199_i63
#ISCELL
  mstr_standard offpage *
  page199_i64
#CELL
  mstr_discrete res *
  page199_i65
#CELL
  dev_discrete cap_a *
  page199_i67
#ISCELL
  mstr_symbols agnd0 *
  page199_i68
#ISCELL
  mstr_standard offpage *
  page199_i69
#CELL
  dev_discrete cap_a *
  page199_i7
#ISCELL
  mstr_standard offpage *
  page199_i71
#ISCELL
  mstr_standard offpage *
  page199_i72
#ISCELL
  mstr_standard offpage *
  page199_i73
#ISCELL
  mstr_standard offpage *
  page199_i74
#ISCELL
  mstr_symbols p12v_stby *
  page199_i75
#ISCELL
  mstr_symbols p12v_stby *
  page199_i76
#ISCELL
  mstr_symbols p12v_stby *
  page199_i77
#ISCELL
  mstr_symbols p12v_psu *
  page199_i79
#CELL
  mstr_discrete fet_n_dual *
  page199_i82
#ISCELL
  mstr_symbols agnd0 *
  page199_i83
#CELL
  mstr_discrete res *
  page199_i84
#CELL
  mstr_discrete res *
  page199_i85
#CELL
  mstr_discrete fet_n_dual *
  page199_i86
#CELL
  mstr_discrete res *
  page199_i87
#CELL
  mstr_discrete res *
  page199_i88
#ISCELL
  mstr_symbols agnd0 *
  page199_i89
#CELL
  mstr_discrete res *
  page199_i9
#ISCELL
  mstr_symbols p12v_psu *
  page199_i90
#CELL
  mstr_discrete res *
  page199_i92
#ISCELL
  mstr_standard offpage *
  page199_i98
#CELL
  mstr_discrete zener *
  page199_i99
